(kicad_pcb
	(version 20260206)
	(generator "pcbnew")
	(generator_version "10.0")
	(general
		(thickness 1.6)
		(legacy_teardrops no)
	)
	(paper "A4")
	(title_block
		(title "Bryce Canyon_F.DPB_16315-1-OCP.brd")
		(comment 1 "Bryce Canyon / footprints 719-726 of 2223")
	)
	(layers
		(0 "F.Cu" signal "TOP")
		(4 "In1.Cu" signal "L2GND")
		(6 "In2.Cu" signal "L3")
		(8 "In3.Cu" signal "L4GND")
		(10 "In4.Cu" signal "L5")
		(12 "In5.Cu" signal "L6VCC")
		(14 "In6.Cu" signal "L7VCC")
		(16 "In7.Cu" signal "L8")
		(18 "In8.Cu" signal "L9GND")
		(20 "In9.Cu" signal "L10")
		(22 "In10.Cu" signal "L11GND")
		(2 "B.Cu" signal "BOTTOM")
		(9 "F.Adhes" user "F.Adhesive")
		(11 "B.Adhes" user "B.Adhesive")
		(13 "F.Paste" user "Package Geometry/Pastemask Top")
		(15 "B.Paste" user "Package Geometry/Pastemask Bottom")
		(5 "F.SilkS" user "Ref Des/Silkscreen Top")
		(7 "B.SilkS" user "Ref Des/Silkscreen Bottom")
		(1 "F.Mask" user "Board Geometry/Soldermask Top")
		(3 "B.Mask" user "Board Geometry/Soldermask Bottom")
		(17 "Dwgs.User" user "User.Drawings")
		(19 "Cmts.User" user "User.Comments")
		(21 "Eco1.User" user "User.Eco1")
		(23 "Eco2.User" user "User.Eco2")
		(25 "Edge.Cuts" user "Board Geometry/Outline")
		(27 "Margin" user)
		(31 "F.CrtYd" user "Package Geometry/Place Bound Top")
		(29 "B.CrtYd" user "Package Geometry/Place Bound Bottom")
		(35 "F.Fab" user "Ref Des/Assembly Top")
		(33 "B.Fab" user "Ref Des/Assembly Bottom")
	)
	(footprint ""
		(layer "F.Cu")
		(at 426.755052 -157.585918)
		(property "Reference" "R625"
			(at 0 0 0)
			(layer "F.SilkS")
			(hide yes)
			(effects
				(font
					(size 1.27 1.27)
				)
			)
		)
		(property "Value" "4K7R2J-2-GP"
			(at 0.064008 -3.993896 0)
			(unlocked yes)
			(layer "F.Fab")
			(hide yes)
			(effects
				(font
					(size 1.016 1.016)
					(thickness 0.1524)
				)
			)
		)
		(property "Device Type" "R402H16"
			(at 0.064008 -5.517896 0)
			(unlocked yes)
			(layer "F.Fab")
			(hide yes)
			(effects
				(font
					(size 1.016 1.016)
					(thickness 0.1524)
				)
			)
		)
		(duplicate_pad_numbers_are_jumpers no)
		(fp_line
			(start -0.508 -0.9398)
			(end -0.508 0.9398)
			(stroke
				(width 0.1524)
				(type default)
			)
			(layer "F.SilkS")
		)
		(fp_line
			(start 0.508 -0.9398)
			(end -0.508 -0.9398)
			(stroke
				(width 0.1524)
				(type default)
			)
			(layer "F.SilkS")
		)
		(fp_rect
			(start -0.508 0.9398)
			(end 0.508 -0.9398)
			(stroke
				(width 0)
				(type default)
			)
			(fill no)
			(layer "F.CrtYd")
		)
		(fp_rect
			(start -0.508 0.9398)
			(end 0.508 -0.9398)
			(stroke
				(width 0)
				(type default)
			)
			(fill no)
			(layer "F.Fab")
		)
		(pad "1" smd custom
			(at 0 -0.4445)
			(size 0.1397 0.1397)
			(layers "F.Cu" "F.Mask" "F.Paste")
			(net "SW_PWR_R_HDD21")
			(options
				(clearance outline)
				(anchor circle)
			)
			(primitives
				(gr_poly
					(pts
						(arc
							(start -0.1778 -0.2794)
							(mid -0.249642 -0.249642)
							(end -0.2794 -0.1778)
						)
						(arc
							(start -0.2794 0.1778)
							(mid -0.249642 0.249642)
							(end -0.1778 0.2794)
						)
						(arc
							(start 0.1778 0.2794)
							(mid 0.249642 0.249642)
							(end 0.2794 0.1778)
						)
						(arc
							(start 0.2794 -0.1778)
							(mid 0.249642 -0.249642)
							(end 0.1778 -0.2794)
						)
					)
					(width 0)
					(fill yes)
				)
			)
		)
		(pad "2" smd custom
			(at 0 0.4445)
			(size 0.1397 0.1397)
			(layers "F.Cu" "F.Mask" "F.Paste")
			(net "GND")
			(options
				(clearance outline)
				(anchor circle)
			)
			(primitives
				(gr_poly
					(pts
						(arc
							(start -0.1778 -0.2794)
							(mid -0.249642 -0.249642)
							(end -0.2794 -0.1778)
						)
						(arc
							(start -0.2794 0.1778)
							(mid -0.249642 0.249642)
							(end -0.1778 0.2794)
						)
						(arc
							(start 0.1778 0.2794)
							(mid 0.249642 0.249642)
							(end 0.2794 0.1778)
						)
						(arc
							(start 0.2794 -0.1778)
							(mid 0.249642 -0.249642)
							(end 0.1778 -0.2794)
						)
					)
					(width 0)
					(fill yes)
				)
			)
		)
	)
	(footprint ""
		(layer "F.Cu")
		(at 18.906998 -179.683918 90)
		(property "Reference" "R407"
			(at 0 0 90)
			(layer "F.SilkS")
			(hide yes)
			(effects
				(font
					(size 1.27 1.27)
				)
			)
		)
		(property "Value" "2R6F-GP"
			(at -0.0508 -4.8514 90)
			(unlocked yes)
			(layer "F.Fab")
			(hide yes)
			(effects
				(font
					(size 1.016 1.016)
					(thickness 0.1524)
				)
			)
		)
		(property "Device Type" "R1206H26"
			(at 0 -6.3754 90)
			(unlocked yes)
			(layer "F.Fab")
			(hide yes)
			(effects
				(font
					(size 1.016 1.016)
					(thickness 0.1524)
				)
			)
		)
		(duplicate_pad_numbers_are_jumpers no)
		(fp_line
			(start 1.016 -2.2352)
			(end 1.016 2.2352)
			(stroke
				(width 0.1524)
				(type default)
			)
			(layer "F.SilkS")
		)
		(fp_line
			(start -1.016 -2.2352)
			(end 1.016 -2.2352)
			(stroke
				(width 0.1524)
				(type default)
			)
			(layer "F.SilkS")
		)
		(fp_line
			(start 1.016 2.2352)
			(end -1.016 2.2352)
			(stroke
				(width 0.1524)
				(type default)
			)
			(layer "F.SilkS")
		)
		(fp_line
			(start -1.016 2.2352)
			(end -1.016 -2.2352)
			(stroke
				(width 0.1524)
				(type default)
			)
			(layer "F.SilkS")
		)
		(fp_rect
			(start -1.0922 2.3114)
			(end 1.0922 -2.3114)
			(stroke
				(width 0)
				(type default)
			)
			(fill no)
			(layer "F.CrtYd")
		)
		(fp_poly
			(pts
				(xy -1.0922 -2.3114) (xy 1.0922 -2.3114) (xy 1.0922 2.3114) (xy -1.0922 2.3114)
			)
			(stroke
				(width 0)
				(type default)
			)
			(fill no)
			(layer "F.Fab")
		)
		(pad "1" smd rect
			(at 0 -1.397 90)
			(size 1.651 1.27)
			(layers "F.Cu" "F.Mask" "F.Paste")
			(net "P12V_HDD12")
		)
		(pad "2" smd rect
			(at 0 1.397 90)
			(size 1.651 1.27)
			(layers "F.Cu" "F.Mask" "F.Paste")
			(net "12V_PRE_12")
		)
	)
	(footprint ""
		(layer "F.Cu")
		(at 149.932898 -177.270918)
		(property "Reference" "R497"
			(at 0 0 0)
			(layer "F.SilkS")
			(hide yes)
			(effects
				(font
					(size 1.27 1.27)
				)
			)
		)
		(property "Value" "2R6F-GP"
			(at -0.0508 -4.8514 0)
			(unlocked yes)
			(layer "F.Fab")
			(hide yes)
			(effects
				(font
					(size 1.016 1.016)
					(thickness 0.1524)
				)
			)
		)
		(property "Device Type" "R1206H26"
			(at 0 -6.3754 0)
			(unlocked yes)
			(layer "F.Fab")
			(hide yes)
			(effects
				(font
					(size 1.016 1.016)
					(thickness 0.1524)
				)
			)
		)
		(duplicate_pad_numbers_are_jumpers no)
		(fp_line
			(start -1.016 -2.2352)
			(end 1.016 -2.2352)
			(stroke
				(width 0.1524)
				(type default)
			)
			(layer "F.SilkS")
		)
		(fp_line
			(start -1.016 2.2352)
			(end -1.016 -2.2352)
			(stroke
				(width 0.1524)
				(type default)
			)
			(layer "F.SilkS")
		)
		(fp_line
			(start 1.016 -2.2352)
			(end 1.016 2.2352)
			(stroke
				(width 0.1524)
				(type default)
			)
			(layer "F.SilkS")
		)
		(fp_line
			(start 1.016 2.2352)
			(end -1.016 2.2352)
			(stroke
				(width 0.1524)
				(type default)
			)
			(layer "F.SilkS")
		)
		(fp_rect
			(start -1.0922 2.3114)
			(end 1.0922 -2.3114)
			(stroke
				(width 0)
				(type default)
			)
			(fill no)
			(layer "F.CrtYd")
		)
		(fp_poly
			(pts
				(xy -1.0922 -2.3114) (xy 1.0922 -2.3114) (xy 1.0922 2.3114) (xy -1.0922 2.3114)
			)
			(stroke
				(width 0)
				(type default)
			)
			(fill no)
			(layer "F.Fab")
		)
		(pad "1" smd rect
			(at 0 -1.397)
			(size 1.651 1.27)
			(layers "F.Cu" "F.Mask" "F.Paste")
			(net "P5V_HDD16")
		)
		(pad "2" smd rect
			(at 0 1.397)
			(size 1.651 1.27)
			(layers "F.Cu" "F.Mask" "F.Paste")
			(net "5V_PRE_16")
		)
	)
	(footprint ""
		(layer "F.Cu")
		(at 224.572322 -150.64867 -90)
		(property "Reference" "TP208"
			(at 0 0 270)
			(layer "F.SilkS")
			(hide yes)
			(effects
				(font
					(size 1.27 1.27)
				)
			)
		)
		(property "Value" "TPAD32-GP"
			(at -0.0508 -1.6764 270)
			(unlocked yes)
			(layer "F.Fab")
			(hide yes)
			(effects
				(font
					(size 1.016 1.016)
					(thickness 0.1524)
				)
			)
		)
		(property "Device Type" "TPAD32"
			(at -0.0508 -3.2004 270)
			(unlocked yes)
			(layer "F.Fab")
			(hide yes)
			(effects
				(font
					(size 1.016 1.016)
					(thickness 0.1524)
				)
			)
		)
		(duplicate_pad_numbers_are_jumpers no)
		(fp_poly
			(pts
				(arc
					(start 0 -0.4064)
					(mid 0 0.4064)
					(end 0 -0.4064)
				)
			)
			(stroke
				(width 0)
				(type default)
			)
			(fill no)
			(layer "F.CrtYd")
		)
		(fp_poly
			(pts
				(arc
					(start 0 -0.7112)
					(mid 0 0.7112)
					(end 0 -0.7112)
				)
			)
			(stroke
				(width 0)
				(type default)
			)
			(fill no)
			(layer "F.Fab")
		)
		(pad "1" smd circle
			(at 0 0 270)
			(size 0.8128 0.8128)
			(layers "F.Cu" "F.Mask" "F.Paste")
			(net "TP_COMP_A_KR_P0_RX_DN")
		)
	)
	(footprint ""
		(layer "F.Cu")
		(at 398.88795 -157.585918 180)
		(property "Reference" "R600"
			(at 0 0 180)
			(layer "F.SilkS")
			(hide yes)
			(effects
				(font
					(size 1.27 1.27)
				)
			)
		)
		(property "Value" "0R2J-2-GP"
			(at 0.064008 -3.993896 180)
			(unlocked yes)
			(layer "F.Fab")
			(hide yes)
			(effects
				(font
					(size 1.016 1.016)
					(thickness 0.1524)
				)
			)
		)
		(property "Device Type" "R402H16"
			(at 0.064008 -5.517896 180)
			(unlocked yes)
			(layer "F.Fab")
			(hide yes)
			(effects
				(font
					(size 1.016 1.016)
					(thickness 0.1524)
				)
			)
		)
		(duplicate_pad_numbers_are_jumpers no)
		(fp_line
			(start 0.508 -0.9398)
			(end -0.508 -0.9398)
			(stroke
				(width 0.1524)
				(type default)
			)
			(layer "F.SilkS")
		)
		(fp_line
			(start -0.508 -0.9398)
			(end -0.508 0.9398)
			(stroke
				(width 0.1524)
				(type default)
			)
			(layer "F.SilkS")
		)
		(fp_rect
			(start -0.508 0.9398)
			(end 0.508 -0.9398)
			(stroke
				(width 0)
				(type default)
			)
			(fill no)
			(layer "F.CrtYd")
		)
		(fp_rect
			(start -0.508 0.9398)
			(end 0.508 -0.9398)
			(stroke
				(width 0)
				(type default)
			)
			(fill no)
			(layer "F.Fab")
		)
		(pad "1" smd custom
			(at 0 -0.4445 180)
			(size 0.1397 0.1397)
			(layers "F.Cu" "F.Mask" "F.Paste")
			(net "DRIVE_A_20_PWR")
			(options
				(clearance outline)
				(anchor circle)
			)
			(primitives
				(gr_poly
					(pts
						(arc
							(start -0.1778 -0.2794)
							(mid -0.249642 -0.249642)
							(end -0.2794 -0.1778)
						)
						(arc
							(start -0.2794 0.1778)
							(mid -0.249642 0.249642)
							(end -0.1778 0.2794)
						)
						(arc
							(start 0.1778 0.2794)
							(mid 0.249642 0.249642)
							(end 0.2794 0.1778)
						)
						(arc
							(start 0.2794 -0.1778)
							(mid 0.249642 -0.249642)
							(end 0.1778 -0.2794)
						)
					)
					(width 0)
					(fill yes)
				)
			)
		)
		(pad "2" smd custom
			(at 0 0.4445 180)
			(size 0.1397 0.1397)
			(layers "F.Cu" "F.Mask" "F.Paste")
			(net "SW_PWR_R_HDD20")
			(options
				(clearance outline)
				(anchor circle)
			)
			(primitives
				(gr_poly
					(pts
						(arc
							(start -0.1778 -0.2794)
							(mid -0.249642 -0.249642)
							(end -0.2794 -0.1778)
						)
						(arc
							(start -0.2794 0.1778)
							(mid -0.249642 0.249642)
							(end -0.1778 0.2794)
						)
						(arc
							(start 0.1778 0.2794)
							(mid 0.249642 0.249642)
							(end 0.2794 0.1778)
						)
						(arc
							(start 0.2794 -0.1778)
							(mid 0.249642 -0.249642)
							(end 0.1778 -0.2794)
						)
					)
					(width 0)
					(fill yes)
				)
			)
		)
	)
	(footprint ""
		(layer "F.Cu")
		(at 364.290102 -279.596342 90)
		(property "Reference" "C139"
			(at 0 0 90)
			(layer "F.SilkS")
			(hide yes)
			(effects
				(font
					(size 1.27 1.27)
				)
			)
		)
		(property "Value" "SCD033U25V2KX-GP"
			(at 1.1811 -2.7051 90)
			(unlocked yes)
			(layer "F.Fab")
			(hide yes)
			(effects
				(font
					(size 1.016 1.016)
					(thickness 0.1524)
				)
			)
		)
		(property "Device Type" "C402H22"
			(at 1.1811 -4.2291 90)
			(unlocked yes)
			(layer "F.Fab")
			(hide yes)
			(effects
				(font
					(size 1.016 1.016)
					(thickness 0.1524)
				)
			)
		)
		(duplicate_pad_numbers_are_jumpers no)
		(fp_rect
			(start -0.4318 0.9525)
			(end 0.4318 -0.9525)
			(stroke
				(width 0)
				(type default)
			)
			(fill no)
			(layer "F.CrtYd")
		)
		(fp_rect
			(start -0.4318 0.9525)
			(end 0.4318 -0.9525)
			(stroke
				(width 0)
				(type default)
			)
			(fill no)
			(layer "F.Fab")
		)
		(pad "1" smd custom
			(at 0 -0.4445 90)
			(size 0.1524 0.1524)
			(layers "F.Cu" "F.Mask" "F.Paste")
			(net "SW_HDD_P7")
			(options
				(clearance outline)
				(anchor circle)
			)
			(primitives
				(gr_poly
					(pts
						(arc
							(start 0.3048 -0.2032)
							(mid 0.275042 -0.275042)
							(end 0.2032 -0.3048)
						)
						(arc
							(start -0.2032 -0.3048)
							(mid -0.275042 -0.275042)
							(end -0.3048 -0.2032)
						)
						(arc
							(start -0.3048 0.2032)
							(mid -0.275042 0.275042)
							(end -0.2032 0.3048)
						)
						(arc
							(start 0.2032 0.3048)
							(mid 0.275042 0.275042)
							(end 0.3048 0.2032)
						)
					)
					(width 0)
					(fill yes)
				)
			)
		)
		(pad "2" smd custom
			(at 0 0.4445 90)
			(size 0.1524 0.1524)
			(layers "F.Cu" "F.Mask" "F.Paste")
			(net "GND")
			(options
				(clearance outline)
				(anchor circle)
			)
			(primitives
				(gr_poly
					(pts
						(arc
							(start 0.3048 -0.2032)
							(mid 0.275042 -0.275042)
							(end 0.2032 -0.3048)
						)
						(arc
							(start -0.2032 -0.3048)
							(mid -0.275042 -0.275042)
							(end -0.3048 -0.2032)
						)
						(arc
							(start -0.3048 0.2032)
							(mid -0.275042 0.275042)
							(end -0.2032 0.3048)
						)
						(arc
							(start 0.2032 0.3048)
							(mid 0.275042 0.275042)
							(end 0.3048 0.2032)
						)
					)
					(width 0)
					(fill yes)
				)
			)
		)
	)
	(footprint ""
		(layer "F.Cu")
		(at 394.56995 -176.127918 -90)
		(property "Reference" "R589"
			(at 0 0 270)
			(layer "F.SilkS")
			(hide yes)
			(effects
				(font
					(size 1.27 1.27)
				)
			)
		)
		(property "Value" "2R6F-GP"
			(at -0.0508 -4.8514 270)
			(unlocked yes)
			(layer "F.Fab")
			(hide yes)
			(effects
				(font
					(size 1.016 1.016)
					(thickness 0.1524)
				)
			)
		)
		(property "Device Type" "R1206H26"
			(at 0 -6.3754 270)
			(unlocked yes)
			(layer "F.Fab")
			(hide yes)
			(effects
				(font
					(size 1.016 1.016)
					(thickness 0.1524)
				)
			)
		)
		(duplicate_pad_numbers_are_jumpers no)
		(fp_line
			(start -1.016 2.2352)
			(end -1.016 -2.2352)
			(stroke
				(width 0.1524)
				(type default)
			)
			(layer "F.SilkS")
		)
		(fp_line
			(start 1.016 2.2352)
			(end -1.016 2.2352)
			(stroke
				(width 0.1524)
				(type default)
			)
			(layer "F.SilkS")
		)
		(fp_line
			(start -1.016 -2.2352)
			(end 1.016 -2.2352)
			(stroke
				(width 0.1524)
				(type default)
			)
			(layer "F.SilkS")
		)
		(fp_line
			(start 1.016 -2.2352)
			(end 1.016 2.2352)
			(stroke
				(width 0.1524)
				(type default)
			)
			(layer "F.SilkS")
		)
		(fp_rect
			(start -1.0922 2.3114)
			(end 1.0922 -2.3114)
			(stroke
				(width 0)
				(type default)
			)
			(fill no)
			(layer "F.CrtYd")
		)
		(fp_poly
			(pts
				(xy -1.0922 -2.3114) (xy 1.0922 -2.3114) (xy 1.0922 2.3114) (xy -1.0922 2.3114)
			)
			(stroke
				(width 0)
				(type default)
			)
			(fill no)
			(layer "F.Fab")
		)
		(pad "1" smd rect
			(at 0 -1.397 270)
			(size 1.651 1.27)
			(layers "F.Cu" "F.Mask" "F.Paste")
			(net "P5V_HDD20")
		)
		(pad "2" smd rect
			(at 0 1.397 270)
			(size 1.651 1.27)
			(layers "F.Cu" "F.Mask" "F.Paste")
			(net "5V_PRE_20")
		)
	)
	(footprint ""
		(layer "F.Cu")
		(at 92.751148 -23.91918)
		(property "Reference" "R983"
			(at 0 0 0)
			(layer "F.SilkS")
			(hide yes)
			(effects
				(font
					(size 1.27 1.27)
				)
			)
		)
		(property "Value" "4K7R2F-GP"
			(at 0.064008 -3.993896 0)
			(unlocked yes)
			(layer "F.Fab")
			(hide yes)
			(effects
				(font
					(size 1.016 1.016)
					(thickness 0.1524)
				)
			)
		)
		(property "Device Type" "R402H16"
			(at 0.064008 -5.517896 0)
			(unlocked yes)
			(layer "F.Fab")
			(hide yes)
			(effects
				(font
					(size 1.016 1.016)
					(thickness 0.1524)
				)
			)
		)
		(duplicate_pad_numbers_are_jumpers no)
		(fp_line
			(start -0.508 -0.9398)
			(end -0.508 0.9398)
			(stroke
				(width 0.1524)
				(type default)
			)
			(layer "F.SilkS")
		)
		(fp_line
			(start 0.508 -0.9398)
			(end -0.508 -0.9398)
			(stroke
				(width 0.1524)
				(type default)
			)
			(layer "F.SilkS")
		)
		(fp_rect
			(start -0.508 0.9398)
			(end 0.508 -0.9398)
			(stroke
				(width 0)
				(type default)
			)
			(fill no)
			(layer "F.CrtYd")
		)
		(fp_rect
			(start -0.508 0.9398)
			(end 0.508 -0.9398)
			(stroke
				(width 0)
				(type default)
			)
			(fill no)
			(layer "F.Fab")
		)
		(pad "1" smd custom
			(at 0 -0.4445)
			(size 0.1397 0.1397)
			(layers "F.Cu" "F.Mask" "F.Paste")
			(net "IOM_A_SLOT_ID_1")
			(options
				(clearance outline)
				(anchor circle)
			)
			(primitives
				(gr_poly
					(pts
						(arc
							(start -0.1778 -0.2794)
							(mid -0.249642 -0.249642)
							(end -0.2794 -0.1778)
						)
						(arc
							(start -0.2794 0.1778)
							(mid -0.249642 0.249642)
							(end -0.1778 0.2794)
						)
						(arc
							(start 0.1778 0.2794)
							(mid 0.249642 0.249642)
							(end 0.2794 0.1778)
						)
						(arc
							(start 0.2794 -0.1778)
							(mid 0.249642 -0.249642)
							(end 0.1778 -0.2794)
						)
					)
					(width 0)
					(fill yes)
				)
			)
		)
		(pad "2" smd custom
			(at 0 0.4445)
			(size 0.1397 0.1397)
			(layers "F.Cu" "F.Mask" "F.Paste")
			(net "GND")
			(options
				(clearance outline)
				(anchor circle)
			)
			(primitives
				(gr_poly
					(pts
						(arc
							(start -0.1778 -0.2794)
							(mid -0.249642 -0.249642)
							(end -0.2794 -0.1778)
						)
						(arc
							(start -0.2794 0.1778)
							(mid -0.249642 0.249642)
							(end -0.1778 0.2794)
						)
						(arc
							(start 0.1778 0.2794)
							(mid 0.249642 0.249642)
							(end 0.2794 0.1778)
						)
						(arc
							(start 0.2794 -0.1778)
							(mid 0.249642 -0.249642)
							(end 0.1778 -0.2794)
						)
					)
					(width 0)
					(fill yes)
				)
			)
		)
	)
)
